# BASEBOARD_FAB2 (Tioga Pass) — schematic netlist excerpt (pin names and nets, part order shuffled) for the footprints in the layout excerpt that follows; sources: Cadence DE-HDL packaged netlist, KiCad conversion of Wiwynn_Tioga_Pass_MB.brd

C5G64  CAP_A  22.0UF 4V 20% X6S  pkg 0603V  page 242 : A = PVDDQ_DEF ; B = GND

U9F2  FSA3357  IC  pkg SM  page 158
  B0  = SP2_BMC_CM_UART_TX_R
  B1  = UART_BMC_TXD5
  B2  = SP1_BMC_HOST_UART_TX
  GND  = GND
  S2  = FM_UARTSW_MSB_N
  S1  = FM_UARTSW_LSB_N
  A  = UART_MUX_OUT_R
  VCC  = P3V3_STBY

R7P3  RES  42.2 1.0% EMPTY  pkg 0402  page 103 : A = CLK_100M_CPU1_PE_REFCLK_DP ; B = GND

(kicad_pcb
	(version 20260206)
	(generator "pcbnew")
	(generator_version "10.0")
	(general
		(thickness 1.6)
		(legacy_teardrops no)
	)
	(paper "A4")
	(title_block
		(title "Wiwynn_Tioga_Pass_MB.brd")
		(comment 1 "Tioga Pass / footprints 2781-2783 of 4770")
	)
	(layers
		(0 "F.Cu" signal "TOP")
		(4 "In1.Cu" signal "L2GND")
		(6 "In2.Cu" signal "L3")
		(8 "In3.Cu" signal "L4GND")
		(10 "In4.Cu" signal "L5")
		(12 "In5.Cu" signal "L6GND")
		(14 "In6.Cu" signal "L7VCC")
		(16 "In7.Cu" signal "L8VCC")
		(18 "In8.Cu" signal "L9GND")
		(20 "In9.Cu" signal "L10")
		(22 "In10.Cu" signal "L11GND")
		(24 "In11.Cu" signal "L12")
		(26 "In12.Cu" signal "L13GND")
		(2 "B.Cu" signal "BOTTOM")
		(9 "F.Adhes" user "F.Adhesive")
		(11 "B.Adhes" user "B.Adhesive")
		(13 "F.Paste" user "Package Geometry/Pastemask Top")
		(15 "B.Paste" user "Package Geometry/Pastemask Bottom")
		(5 "F.SilkS" user "Ref Des/Silkscreen Top")
		(7 "B.SilkS" user "Ref Des/Silkscreen Bottom")
		(1 "F.Mask" user "Board Geometry/Soldermask Top")
		(3 "B.Mask" user "Board Geometry/Soldermask Bottom")
		(17 "Dwgs.User" user "User.Drawings")
		(19 "Cmts.User" user "User.Comments")
		(21 "Eco1.User" user "User.Eco1")
		(23 "Eco2.User" user "User.Eco2")
		(25 "Edge.Cuts" user "Board Geometry/Outline")
		(27 "Margin" user)
		(31 "F.CrtYd" user "Package Geometry/Place Bound Top")
		(29 "B.CrtYd" user "Package Geometry/Place Bound Bottom")
		(35 "F.Fab" user "Ref Des/Assembly Top")
		(33 "B.Fab" user "Ref Des/Assembly Bottom")
	)
	(footprint ""
		(layer "B.Cu")
		(at 245.7323 -140.208 -90)
		(property "Reference" "C5G64"
			(at -1.14681 0.76708 0)
			(unlocked yes)
			(layer "B.SilkS")
			(effects
				(font
					(size 0.7874 0.5842)
					(thickness 0.1524)
				)
				(justify mirror)
			)
		)
		(property "Value" ""
			(at 0 0 90)
			(layer "B.Fab")
			(effects
				(font
					(size 1.27 1.27)
				)
				(justify mirror)
			)
		)
		(duplicate_pad_numbers_are_jumpers no)
		(fp_rect
			(start 0.4953 1.6002)
			(end -0.4953 -0.2032)
			(stroke
				(width 0)
				(type default)
			)
			(fill no)
			(layer "B.CrtYd")
		)
		(fp_line
			(start -0.4953 1.6002)
			(end 0.4953 1.6002)
			(stroke
				(width 0.1)
				(type default)
			)
			(layer "B.Fab")
		)
		(fp_line
			(start 0.4953 1.6002)
			(end 0.4953 -0.2032)
			(stroke
				(width 0.1)
				(type default)
			)
			(layer "B.Fab")
		)
		(fp_line
			(start -0.4953 -0.2032)
			(end -0.4953 1.6002)
			(stroke
				(width 0.1)
				(type default)
			)
			(layer "B.Fab")
		)
		(fp_line
			(start 0.4953 -0.2032)
			(end -0.4953 -0.2032)
			(stroke
				(width 0.1)
				(type default)
			)
			(layer "B.Fab")
		)
		(pad "1" smd rect
			(at 0 0 90)
			(size 0.762 0.889)
			(layers "B.Cu" "B.Mask" "B.Paste")
			(net "PVDDQ_DEF")
		)
		(pad "2" smd rect
			(at 0 1.397 90)
			(size 0.762 0.889)
			(layers "B.Cu" "B.Mask" "B.Paste")
			(net "GND")
		)
		(zone
			(layer "B.Cu")
			(hatch none 0.5)
			(connect_pads
				(clearance 0)
			)
			(min_thickness 0.25)
			(keepout
				(tracks not_allowed)
				(vias allowed)
				(pads allowed)
				(copperpour not_allowed)
				(footprints allowed)
			)
			(placement
				(enabled no)
				(sheetname "")
			)
			(fill
				(thermal_gap 0.5)
				(thermal_bridge_width 0.5)
				(island_removal_mode 0)
			)
			(polygon
				(pts
					(xy 244.7798 -139.827) (xy 245.2878 -139.827) (xy 245.2878 -140.589) (xy 244.7798 -140.589)
				)
			)
		)
	)
	(footprint ""
		(layer "B.Cu")
		(at 496.919504 -35.458146 180)
		(property "Reference" "U9F2"
			(at 0.4064 2.41427 180)
			(unlocked yes)
			(layer "B.SilkS")
			(effects
				(font
					(size 0.7874 0.5842)
					(thickness 0.1524)
				)
				(justify mirror)
			)
		)
		(property "Value" ""
			(at 0 0 0)
			(layer "B.Fab")
			(effects
				(font
					(size 1.27 1.27)
				)
				(justify mirror)
			)
		)
		(duplicate_pad_numbers_are_jumpers no)
		(fp_line
			(start -1.269238 1.8034)
			(end -1.77673 1.8034)
			(stroke
				(width 0.1524)
				(type default)
			)
			(layer "B.SilkS")
		)
		(fp_line
			(start -1.269238 -0.3048)
			(end -1.77673 -0.3048)
			(stroke
				(width 0.1524)
				(type default)
			)
			(layer "B.SilkS")
		)
		(fp_circle
			(center 0.967994 -0.635)
			(end 0.840994 -0.635)
			(stroke
				(width 0.254)
				(type default)
			)
			(fill no)
			(layer "B.SilkS")
		)
		(fp_rect
			(start -0.3302 1.8034)
			(end -2.7432 -0.3048)
			(stroke
				(width 0)
				(type default)
			)
			(fill no)
			(layer "B.CrtYd")
		)
		(fp_line
			(start -0.3302 1.8034)
			(end -0.3302 -0.3048)
			(stroke
				(width 0.1)
				(type default)
			)
			(layer "B.Fab")
		)
		(fp_line
			(start -0.3302 -0.3048)
			(end -2.7432 -0.3048)
			(stroke
				(width 0.1)
				(type default)
			)
			(layer "B.Fab")
		)
		(fp_line
			(start -2.7432 1.8034)
			(end -0.3302 1.8034)
			(stroke
				(width 0.1)
				(type default)
			)
			(layer "B.Fab")
		)
		(fp_line
			(start -2.7432 -0.3048)
			(end -2.7432 1.8034)
			(stroke
				(width 0.1)
				(type default)
			)
			(layer "B.Fab")
		)
		(fp_circle
			(center 0.967994 -0.635)
			(end 0.840994 -0.635)
			(stroke
				(width 0.254)
				(type default)
			)
			(fill no)
			(layer "B.Fab")
		)
		(pad "1" smd rect
			(at 0 0)
			(size 1.524 0.254)
			(layers "B.Cu" "B.Mask" "B.Paste")
			(net "SP2_BMC_CM_UART_TX_R")
		)
		(pad "2" smd rect
			(at 0 0.499872)
			(size 1.524 0.254)
			(layers "B.Cu" "B.Mask" "B.Paste")
			(net "UART_BMC_TXD5")
		)
		(pad "3" smd rect
			(at 0 0.999744)
			(size 1.524 0.254)
			(layers "B.Cu" "B.Mask" "B.Paste")
			(net "SP1_BMC_HOST_UART_TX")
		)
		(pad "4" smd rect
			(at 0 1.499616)
			(size 1.524 0.254)
			(layers "B.Cu" "B.Mask" "B.Paste")
			(net "GND")
		)
		(pad "5" smd rect
			(at -3.048 1.499616)
			(size 1.524 0.254)
			(layers "B.Cu" "B.Mask" "B.Paste")
			(net "FM_UARTSW_MSB_N")
		)
		(pad "6" smd rect
			(at -3.048 0.999744)
			(size 1.524 0.254)
			(layers "B.Cu" "B.Mask" "B.Paste")
			(net "FM_UARTSW_LSB_N")
		)
		(pad "7" smd rect
			(at -3.048 0.499872)
			(size 1.524 0.254)
			(layers "B.Cu" "B.Mask" "B.Paste")
			(net "UART_MUX_OUT_R")
		)
		(pad "8" smd rect
			(at -3.048 0)
			(size 1.524 0.254)
			(layers "B.Cu" "B.Mask" "B.Paste")
			(net "P3V3_STBY")
		)
	)
	(footprint ""
		(layer "B.Cu")
		(at 162.687 -83.058 90)
		(property "Reference" "R7P3"
			(at 0 0 90)
			(layer "B.SilkS")
			(hide yes)
			(effects
				(font
					(size 1.27 1.27)
				)
				(justify mirror)
			)
		)
		(property "Value" ""
			(at 0 0 90)
			(layer "B.Fab")
			(effects
				(font
					(size 1.27 1.27)
				)
				(justify mirror)
			)
		)
		(duplicate_pad_numbers_are_jumpers no)
		(fp_poly
			(pts
				(xy 0.2794 -0.1016) (xy -0.2794 -0.1016) (xy -0.2794 0.9906) (xy 0.2794 0.9906)
			)
			(stroke
				(width 0)
				(type default)
			)
			(fill no)
			(layer "B.CrtYd")
		)
		(fp_line
			(start 0.2794 -0.1016)
			(end 0.2794 0.9906)
			(stroke
				(width 0.1)
				(type default)
			)
			(layer "B.Fab")
		)
		(fp_line
			(start -0.2794 -0.1016)
			(end 0.2794 -0.1016)
			(stroke
				(width 0.1)
				(type default)
			)
			(layer "B.Fab")
		)
		(fp_line
			(start 0.2794 0.9906)
			(end -0.2794 0.9906)
			(stroke
				(width 0.1)
				(type default)
			)
			(layer "B.Fab")
		)
		(fp_line
			(start -0.2794 0.9906)
			(end -0.2794 -0.1016)
			(stroke
				(width 0.1)
				(type default)
			)
			(layer "B.Fab")
		)
		(pad "1" smd rect
			(at 0 0 270)
			(size 0.508 0.508)
			(layers "B.Cu" "B.Mask" "B.Paste")
			(net "CLK_100M_CPU1_PE_REFCLK_DP")
		)
		(pad "2" smd rect
			(at 0 0.889 270)
			(size 0.508 0.508)
			(layers "B.Cu" "B.Mask" "B.Paste")
			(net "GND")
		)
		(zone
			(layer "B.Cu")
			(hatch none 0.5)
			(connect_pads
				(clearance 0)
			)
			(min_thickness 0.25)
			(keepout
				(tracks allowed)
				(vias not_allowed)
				(pads allowed)
				(copperpour not_allowed)
				(footprints allowed)
			)
			(placement
				(enabled no)
				(sheetname "")
			)
			(fill
				(thermal_gap 0.5)
				(thermal_bridge_width 0.5)
				(island_removal_mode 0)
			)
			(polygon
				(pts
					(xy 162.941 -83.312) (xy 162.941 -82.804) (xy 163.322 -82.804) (xy 163.322 -83.312)
				)
			)
		)
		(zone
			(layer "B.Cu")
			(hatch none 0.5)
			(connect_pads
				(clearance 0)
			)
			(min_thickness 0.25)
			(keepout
				(tracks not_allowed)
				(vias allowed)
				(pads allowed)
				(copperpour not_allowed)
				(footprints allowed)
			)
			(placement
				(enabled no)
				(sheetname "")
			)
			(fill
				(thermal_gap 0.5)
				(thermal_bridge_width 0.5)
				(island_removal_mode 0)
			)
			(polygon
				(pts
					(xy 163.322 -83.312) (xy 163.322 -82.804) (xy 162.941 -82.804) (xy 162.941 -83.312)
				)
			)
		)
	)
)
